# TIMECARD (Time Appliance Project (Time Card)) — schematic netlist excerpt (pin names and nets, part order shuffled) for the footprints in the layout excerpt that follows; sources: Cadence DE-HDL packaged netlist, KiCad conversion of R4006-B0001-02_R01.brd

R350  RESISTOR  0OHM -  pkg SMC_0402R_H016  page 19 : \1\ = UNNAMED_8_ICP10100LGA10_I24_R_3 ; \2\ = XP1R8V_ICP10100
TP39  TP_PIONT  pkg TP010CT020B030_PTH  page 25 : \1\ = XP1R0V_FPGA_PG

(kicad_pcb
	(version 20260206)
	(generator "pcbnew")
	(generator_version "10.0")
	(general
		(thickness 1.6)
		(legacy_teardrops no)
	)
	(paper "A4")
	(title_block
		(title "timecard-production-celestica-r4006 — R4006-B0001-02_R01.brd")
		(comment 1 "Time Appliance Project (Time Card) / footprints 237-238 of 1113")
	)
	(layers
		(0 "F.Cu" signal "TOP")
		(4 "In1.Cu" signal "L02_GND1")
		(6 "In2.Cu" signal "L03_SIG1")
		(8 "In3.Cu" signal "L04_GND2")
		(10 "In4.Cu" signal "L05_VCC1")
		(12 "In5.Cu" signal "L06_VCC2")
		(14 "In6.Cu" signal "L07_GND3")
		(16 "In7.Cu" signal "L08_SIG2")
		(18 "In8.Cu" signal "L09_GND4")
		(2 "B.Cu" signal "BOTTOM")
		(9 "F.Adhes" user "F.Adhesive")
		(11 "B.Adhes" user "B.Adhesive")
		(13 "F.Paste" user "Package Geometry/Pastemask Top")
		(15 "B.Paste" user "Package Geometry/Pastemask Bottom")
		(5 "F.SilkS" user "Ref Des/Silkscreen Top")
		(7 "B.SilkS" user "Ref Des/Silkscreen Bottom")
		(1 "F.Mask" user "Board Geometry/Soldermask Top")
		(3 "B.Mask" user "Board Geometry/Soldermask Bottom")
		(17 "Dwgs.User" user "User.Drawings")
		(19 "Cmts.User" user "User.Comments")
		(21 "Eco1.User" user "User.Eco1")
		(23 "Eco2.User" user "User.Eco2")
		(25 "Edge.Cuts" user "Board Geometry/Outline")
		(27 "Margin" user)
		(31 "F.CrtYd" user "Package Geometry/Place Bound Top")
		(29 "B.CrtYd" user "Package Geometry/Place Bound Bottom")
		(35 "F.Fab" user "Ref Des/Assembly Top")
		(33 "B.Fab" user "Ref Des/Assembly Bottom")
	)
	(footprint ""
		(layer "F.Cu")
		(at 19.544792 -64.6684 -90)
		(property "Reference" "R350"
			(at 1.2954 -4.751578 90)
			(unlocked yes)
			(layer "F.SilkS")
			(effects
				(font
					(size 0.7874 0.5842)
					(thickness 0.1524)
				)
			)
		)
		(property "Value" "VAL*"
			(at 0.02032 2.13233 270)
			(unlocked yes)
			(layer "F.Fab")
			(hide yes)
			(effects
				(font
					(size 0.7874 0.5842)
					(thickness 0.1524)
				)
			)
		)
		(property "Tolerance" "TOL*"
			(at 0.044704 3.05435 270)
			(unlocked yes)
			(layer "Cmts.User")
			(hide yes)
			(effects
				(font
					(size 0.7874 0.5842)
					(thickness 0.1524)
				)
			)
		)
		(property "User Part Number" "PARTNUM*"
			(at 0.02032 4.024884 270)
			(unlocked yes)
			(layer "Cmts.User")
			(hide yes)
			(effects
				(font
					(size 0.7874 0.5842)
					(thickness 0.1524)
				)
			)
		)
		(property "Device Type" "RESISTOR-G155-100R0-J0,0OHM,-"
			(at 0.008382 1.210564 270)
			(unlocked yes)
			(layer "F.Fab")
			(hide yes)
			(effects
				(font
					(size 0.7874 0.5842)
					(thickness 0.1524)
				)
			)
		)
		(duplicate_pad_numbers_are_jumpers no)
		(fp_line
			(start -1.143 0.5588)
			(end 1.143 0.5588)
			(stroke
				(width 0.1)
				(type default)
			)
			(layer "F.SilkS")
		)
		(fp_line
			(start 1.143 0.5588)
			(end 1.143 -0.5588)
			(stroke
				(width 0.1)
				(type default)
			)
			(layer "F.SilkS")
		)
		(fp_line
			(start -1.143 -0.5588)
			(end -1.143 0.5588)
			(stroke
				(width 0.1)
				(type default)
			)
			(layer "F.SilkS")
		)
		(fp_line
			(start 1.143 -0.5588)
			(end -1.143 -0.5588)
			(stroke
				(width 0.1)
				(type default)
			)
			(layer "F.SilkS")
		)
		(fp_poly
			(pts
				(xy -1.143 0.5588) (xy 1.143 0.5588) (xy 1.143 -0.5588) (xy -1.143 -0.5588)
			)
			(stroke
				(width 0)
				(type default)
			)
			(fill no)
			(layer "F.CrtYd")
		)
		(fp_line
			(start -0.508 0.3048)
			(end 0.508 0.3048)
			(stroke
				(width 0.1)
				(type default)
			)
			(layer "F.Fab")
		)
		(fp_line
			(start 0.508 0.3048)
			(end 0.508 -0.3048)
			(stroke
				(width 0.1)
				(type default)
			)
			(layer "F.Fab")
		)
		(fp_line
			(start -0.508 -0.3048)
			(end -0.508 0.3048)
			(stroke
				(width 0.1)
				(type default)
			)
			(layer "F.Fab")
		)
		(fp_line
			(start 0.508 -0.3048)
			(end -0.508 -0.3048)
			(stroke
				(width 0.1)
				(type default)
			)
			(layer "F.Fab")
		)
		(pad "1" smd rect
			(at -0.5334 0 270)
			(size 0.7112 0.6096)
			(layers "F.Cu" "F.Mask" "F.Paste")
			(net "UNNAMED_8_ICP10100LGA10_I24_R_3")
		)
		(pad "2" smd rect
			(at 0.5334 0 270)
			(size 0.7112 0.6096)
			(layers "F.Cu" "F.Mask" "F.Paste")
			(net "XP1R8V_ICP10100")
		)
		(zone
			(layer "F.Cu")
			(hatch none 0.5)
			(connect_pads
				(clearance 0)
			)
			(min_thickness 0.25)
			(keepout
				(tracks not_allowed)
				(vias allowed)
				(pads allowed)
				(copperpour not_allowed)
				(footprints allowed)
			)
			(placement
				(enabled no)
				(sheetname "")
			)
			(fill
				(thermal_gap 0.5)
				(thermal_bridge_width 0.5)
				(island_removal_mode 0)
			)
			(polygon
				(pts
					(xy 19.239992 -64.7446) (xy 19.239992 -64.5922) (xy 19.849592 -64.5922) (xy 19.849592 -64.7446)
				)
			)
		)
		(zone
			(layer "F.Cu")
			(hatch none 0.5)
			(connect_pads
				(clearance 0)
			)
			(min_thickness 0.25)
			(keepout
				(tracks allowed)
				(vias not_allowed)
				(pads allowed)
				(copperpour not_allowed)
				(footprints allowed)
			)
			(placement
				(enabled no)
				(sheetname "")
			)
			(fill
				(thermal_gap 0.5)
				(thermal_bridge_width 0.5)
				(island_removal_mode 0)
			)
			(polygon
				(pts
					(xy 19.239992 -64.7446) (xy 19.239992 -64.5922) (xy 19.849592 -64.5922) (xy 19.849592 -64.7446)
				)
			)
		)
	)
	(footprint ""
		(layer "F.Cu")
		(at 146.304 -62.611)
		(property "Reference" "TP39"
			(at -1.7272 -1.35763 0)
			(unlocked yes)
			(layer "F.SilkS")
			(effects
				(font
					(size 0.7874 0.5842)
					(thickness 0.1524)
				)
				(justify left)
			)
		)
		(property "Value" ""
			(at 0 0 0)
			(layer "F.Fab")
			(effects
				(font
					(size 1.27 1.27)
				)
			)
		)
		(property "Device Type" "TP_PIONT-TP010CT020B030_PTH-TPA"
			(at -1.341882 0.996696 0)
			(unlocked yes)
			(layer "F.Fab")
			(hide yes)
			(effects
				(font
					(size 0.7874 0.5842)
					(thickness 0.000001)
				)
				(justify left)
			)
		)
		(duplicate_pad_numbers_are_jumpers no)
		(fp_poly
			(pts
				(arc
					(start 0.889 0)
					(mid -0.889 0)
					(end 0.889 0)
				)
			)
			(stroke
				(width 0)
				(type default)
			)
			(fill no)
			(layer "B.CrtYd")
		)
		(fp_poly
			(pts
				(arc
					(start 0.889 0)
					(mid -0.889 0)
					(end 0.889 0)
				)
			)
			(stroke
				(width 0)
				(type default)
			)
			(fill no)
			(layer "F.CrtYd")
		)
		(pad "1" thru_hole circle
			(at 0 0)
			(size 0.508 0.508)
			(drill 0.254)
			(layers "*.Cu" "*.Mask")
			(remove_unused_layers no)
			(net "XP1R0V_FPGA_PG")
			(clearance 0.1016)
			(padstack
				(mode front_inner_back)
				(layer "Inner"
					(shape circle)
					(size 0.508 0.508)
					(clearance 0.1016)
				)
				(layer "B.Cu"
					(shape circle)
					(size 0.762 0.762)
					(clearance -0.0254)
				)
			)
		)
	)
)
